# SCM (Grand Teton) — schematic netlist excerpt (pin names and nets, part order shuffled) for the footprints in the layout excerpt that follows; sources: Cadence DE-HDL packaged netlist, KiCad conversion of 12092022_DA0F0TMDCD0_F0T_Management_Board_D_brd_V3_OCP.brd

GF1  FCONN168_ME1016810202011_SCM  EMPTY  pkg GOLD_168P_ME1016813401311  page 10
  I2C_0_SCL  = SMB_BMC_MM14_R1_SCL
  I2C_0_SDA  = SMB_BMC_MM14_R1_SDA
  I2C_1_SCL  = SMB_BMC_MM1_SCL
  I2C_1_SDA  = SMB_BMC_MM1_SDA
  I2C_2_SCL  = SMB_BMC_MM2_SCL_R1
  I2C_2_SDA  = SMB_BMC_MM2_SDA
  I2C_3_SCL  = SMB_BMC_MM3_SCL
  I2C_3_SDA  = SMB_BMC_MM3_SDA
  I2C_4_SCL  = SMB_BMC_MM4_SCL
  I2C_4_SDA  = SMB_BMC_MM4_SDA
  I2C_5_SCL  = SMB_BMC_MM5_SCL
  I2C_5_SDA  = SMB_BMC_MM5_SDA
  GND_A13  = GND
  CLK_100M_PCIE_DP  = CLK_100M_PCH_DP
  CLK_100M_PCIE_DN  = CLK_100M_PCH_DN
  GND_A16  = GND
  PCIE_BMC_TX_DP  = P2E_PCH_RX_DP
  PCIE_BMC_TX_DN  = P2E_PCH_RX_DN
  GND_A19  = GND
  PCIE_BMC_RX_DP  = P2E_PCH_TX_C_DP
  PCIE_BMC_RX_DN  = P2E_PCH_TX_C_DN
  GND_A22  = GND
  I2C_6_SCL  = SMB_BMC_MM6_SCL
  I2C_6_SDA  = SMB_BMC_MM6_SDA
  I2C_7_SCL  = SMB_BMC_MM7_SCL
  I2C_7_SDA  = SMB_BMC_MM7_SDA
  I2C_8_SCL  = SMB_BMC_MM8_SCL
  I2C_8_SDA  = SMB_BMC_MM8_SDA
  I2C_9_SCL  = SMB_BMC_MM9_SCL
  I2C_9_SDA  = SMB_BMC_MM9_SDA
  I2C_10_SCL  = SMB_BMC_MM10_SCL
  I2C_10_SDA  = SMB_BMC_MM10_SDA
  GND_A33  = GND
  JTAG_TCK  = JTAG_MB_TCK
  JTAG_TMS  = JTAG_MB_TMS
  JTAG_TDI  = JTAG_MB_TDI
  JTAG_TDO  = JTAG_MB_TDO
  I2C_11_SCL  = SMB_BMC_MM12_SCL
  I2C_11_SDA  = SMB_BMC_MM12_SDA
  I2C_12_SCL  = SMB_BMC_MM13_SCL
  I2C_12_SDA  = SMB_BMC_MM13_SDA
  GND_A42  = GND
  HPM_FW_RECOVERY  = FM_JTAG_SEL
  HPM_STBY_RDY  = PWRGD_PSU_AC_PWROK_R
  HPM_STBY_EN  = TP_GF_A45
  HPM_STBY_RST_N  = RST_MB_STBY_N
  SYS_PWRBTN_N  = SYS_PWRBTN_N
  SYS_PWROK  = PWRGD_SYS_PWROK
  DBP_PREQ_N  = FM_DBP_CPU_PREQ_GF_R_N
  DBP_PRDY_N  = FM_DBP_BMC_PRDY_N
  RST_PLTRST_BUF_N  = RST_PLTRST_N
  SPARE1  = FM_BMC_UARTSW_MSB_N
  ROT_CPU_RST_N  = RST_ROT_CPU_N
  CHASI_N  = FM_INTRUDER_N
  SPARE0  = FM_BMC_UARTSW_LSB_N
  IRQ_N  = IRQ_SMI_ACTIVE_GF_N
  PRSNT1_N  = FM_PRSNT_1_N
  GND_A58  = GND
  PCIE_HPM_RXP_0  = USB3_FPNL_RXP
  PCIE_HPM_RXN_0  = USB3_FPNL_RXN
  GND_A61  = GND
  PCIE_HPM_RXP_1  = TP_GF_A62
  PCIE_HPM_RXN_1  = TP_GF_A63
  GND_A64  = GND
  PCIE_HPM_RXP_2  = P2E_GPU_RX_DP
  PCIE_HPM_RXN_2  = P2E_GPU_RX_DN
  GND_A67  = GND
  PCIE_HPM_RXP_3  = CLK_100M_GPU_DP
  PCIE_HPM_RXN_3  = CLK_100M_GPU_DN
  GND_A70  = GND
  ESPI_CLK  = ESPI_HOST_LPC_BMC_CLK
  ESPI_CS0_N  = ESPI_HOST_LPC_BMC_LFRAME_N
  ESPI_ALERT_N  = IRQ_BMC_LPC_SERIRQ_ESPI_GF
  ESPI_RESET_N  = RST_BMC_LPC_ESPI_N
  ESPI_IO0  = ESPI_LPC_LAD0_IO0
  ESPI_IO1  = ESPI_LPC_LAD1_IO1
  ESPI_IO2  = ESPI_LPC_LAD2_IO2
  ESPI_IO3  = ESPI_LPC_LAD3_IO3
  RSVD3  = LPC_ESPI_SEL
  GND_B10  = GND
  QSPI0_CLK  = SPI_SYS_R_CLK
  QSPI0_CS0_N  = SPI_SYS_CS0_N
  QSPI0_D0  = SPI_SYS_R_MOSI
  QSPI0_D1  = SPI_SYS_R_MISO
  QSPI0_D2  = SPI_SYS_WP_R_IO2
  QSPI0_D3  = SPI_SYS_HOLD_R_IO3
  GND_B17  = GND
  NCSI_CLK  = RMII_OCP_RCLKI
  NCSI_CRS_DV  = RMII_CSRDV
  NCSI_TXEN  = RMII_TXEN
  NCSI_TXD0  = RMII_TXD0
  NCSI_TXD1  = RMII_TXD1
  NCSI_RXER  = RMII_RXER
  NCSI_RXD0  = RMII_RXD0
  NCSI_RXD1  = RMII_RXD1
  GND_B26  = GND
  PECI_BMC  = PECI_BMC
  PVCCIO_PECI  = PVCCIO_PECI_BMC
  SGPIO0_DO  = SGPIO_DO_0
  SGPIO_CLK  = SGPIO_CLK_0
  SGPIO0_DI  = SGPIO_DI_0
  SGPIO0_LD  = SGPIO_LD_0
  GND_B33  = GND
  SGPIO1_DO  = SGPIO_DO_1
  RSVD2  = SGPIO_CLK_1
  SGPIO1_DI  = SGPIO_DI_1
  SGPIO1_LD  = SGPIO_LD_1
  GND_B38  = GND
  SGPIO_RESET_N  = RST_SGPIO_RESET_N
  SGPIO_INTR_N  = IRQ_SGPIO_N
  P3V0_BAT  = P3V_BAT_R
  QSPI0_CS1_N  = AC_PWR_BTN_N
  QSPI1_CLK  = QSPI_2_PLD_CLK
  QSPI1_CS0_N  = TP_GF1_B44
  QSPI1_D0  = QSPI_2_PLD_IO0
  QSPI1_D1  = QSPI_2_PLD_IO1
  QSPI1_D2  = QSPI_2_PLD_IO2
  QSPI1_D3  = QSPI_2_PLD_IO3
  GND_B49  = GND
  USB2_DP  = USB_HOST_BMC_B_DP
  USB2_DN  = USB_HOST_BMC_B_DN
  GND_B52  = GND
  USB1_DP  = USB_HOST_BMC_A_DP
  USB1_DN  = USB_HOST_BMC_A_DN
  GND_B55  = GND
  RSVD0  = USB_FPNL_DP
  RSVD1  = USB_FPNL_DN
  GND_B58  = GND
  PCIE_HPM_TXP_0  = USB3_FPNL_TXP
  PCIE_HPM_TXN_0  = USB3_FPNL_TXN
  GND_B61  = GND
  PCIE_HPM_TXP_1  = TP_GF_B62
  PCIE_HPM_TXN_1  = TP_GF_B63
  GND_B64  = GND
  PCIE_HPM_TXP_2  = P2E_GPU_TX_C_DP
  PCIE_HPM_TXN_2  = P2E_GPU_TX_C_DN
  GND_B67  = GND
  PCIE_HPM_TXP_3  = HDD_LED_R_N
  PCIE_HPM_TXN_3  = PCH_BEEP_R_LED
  GND_B70  = GND
  P12V_AUX_OA1  = P12V_AUX
  P12V_AUX_OA2  = P12V_AUX
  GND_OA3  = GND
  GND_OA4  = GND
  I3C_0_SCL  = I3C1_SPD_SCL
  I3C_0_SDA  = I3C1_SPD_SDA
  I3C_1_SCL  = I3C2_SPD_SCL
  I3C_1_SDA  = I3C2_SPD_SDA
  I3C_2_SCL  = I3C3_SPD_SCL
  I3C_2_SDA  = I3C3_SPD_SDA
  I3C_3_SCL  = I3C4_SPD_SCL
  I3C_3_SDA  = I3C4_SPD_SDA
  GND_OA13  = GND
  VIRTUAL_RESEAT  = FM_VIRTUAL_RESEAT
  P12V_AUX_OB1  = P12V_AUX
  P12V_AUX_OB2  = P12V_AUX
  PRSNT0_N  = FM_PRSNT_0_R_N
  GND_OB4  = GND
  UART1_SCM_TX  = UART_BIC_GF_TXD
  UART1_SCM_RX  = UART_BIC_GF_RXD
  GND_OB7  = GND
  UART0_SCM_TX  = UART_SYS_DBG_TX
  UART0_SCM_RX  = UART_SYS_DBG_RX
  GND_OB10  = GND
  SPI0_CLK  = RST_SRST_PLD_BMC_R_N
  SPI0_CS_N  = SPI_TPM_CS_N
  SPI0_MOSI  = H_CPU_CATERR_LVC2_R2_N
  SPI0_MISO  = FM_SOL_UART_CH_SEL

(kicad_pcb
	(version 20260206)
	(generator "pcbnew")
	(generator_version "10.0")
	(general
		(thickness 1.6)
		(legacy_teardrops no)
	)
	(paper "A4")
	(title_block
		(title "12092022_DA0F0TMDCD0_F0T_Management_Board_D_brd_V3_OCP.brd")
		(comment 1 "Grand Teton / footprint 804 of 1440 (GF1), pads 145-168 of 168")
	)
	(layers
		(0 "F.Cu" signal "TOP")
		(4 "In1.Cu" signal "GND")
		(6 "In2.Cu" signal "IN1")
		(8 "In3.Cu" signal "GND1")
		(10 "In4.Cu" signal "IN2")
		(12 "In5.Cu" signal "VCC")
		(14 "In6.Cu" signal "VCC1")
		(16 "In7.Cu" signal "IN3")
		(18 "In8.Cu" signal "GND2")
		(20 "In9.Cu" signal "IN4")
		(22 "In10.Cu" signal "GND3")
		(2 "B.Cu" signal "BOTTOM")
		(9 "F.Adhes" user "F.Adhesive")
		(11 "B.Adhes" user "B.Adhesive")
		(13 "F.Paste" user "Package Geometry/Pastemask Top")
		(15 "B.Paste" user "Package Geometry/Pastemask Bottom")
		(5 "F.SilkS" user "Ref Des/Silkscreen Top")
		(7 "B.SilkS" user "Ref Des/Silkscreen Bottom")
		(1 "F.Mask" user "Board Geometry/Soldermask Top")
		(3 "B.Mask" user "Board Geometry/Soldermask Bottom")
		(17 "Dwgs.User" user "User.Drawings")
		(19 "Cmts.User" user "User.Comments")
		(21 "Eco1.User" user "User.Eco1")
		(23 "Eco2.User" user "User.Eco2")
		(25 "Edge.Cuts" user "Board Geometry/Outline")
		(27 "Margin" user)
		(31 "F.CrtYd" user "Package Geometry/Place Bound Top")
		(29 "B.CrtYd" user "Package Geometry/Place Bound Bottom")
		(35 "F.Fab" user "Ref Des/Assembly Top")
		(33 "B.Fab" user "Ref Des/Assembly Bottom")
	)
	(footprint ""
		(layer "B.Cu")
		(at 45.260006 -114.324892 180)
		(property "Reference" "GF1"
			(at 30.591506 -4.763262 0)
			(unlocked yes)
			(layer "B.SilkS")
			(effects
				(font
					(size 0.7874 0.5842)
					(thickness 0.1524)
				)
				(justify left mirror)
			)
		)
		(property "Value" ""
			(at 0 0 0)
			(layer "B.Fab")
			(effects
				(font
					(size 1.27 1.27)
				)
				(justify mirror)
			)
		)
		(duplicate_pad_numbers_are_jumpers no)
		(pad "OA5" smd rect
			(at -27.999944 4.13512)
			(size 0.381 2.1336)
			(layers "B.Cu" "B.Mask" "B.Paste")
			(net "I3C1_SPD_SCL")
		)
		(pad "OA6" smd rect
			(at -27.399996 4.13512)
			(size 0.381 2.1336)
			(layers "B.Cu" "B.Mask" "B.Paste")
			(net "I3C1_SPD_SDA")
		)
		(pad "OA7" smd rect
			(at -26.800048 4.13512)
			(size 0.381 2.1336)
			(layers "B.Cu" "B.Mask" "B.Paste")
			(net "I3C2_SPD_SCL")
		)
		(pad "OA8" smd rect
			(at -26.2001 4.13512)
			(size 0.381 2.1336)
			(layers "B.Cu" "B.Mask" "B.Paste")
			(net "I3C2_SPD_SDA")
		)
		(pad "OA9" smd rect
			(at -25.599898 4.13512)
			(size 0.381 2.1336)
			(layers "B.Cu" "B.Mask" "B.Paste")
			(net "I3C3_SPD_SCL")
		)
		(pad "OA10" smd rect
			(at -24.99995 4.13512)
			(size 0.381 2.1336)
			(layers "B.Cu" "B.Mask" "B.Paste")
			(net "I3C3_SPD_SDA")
		)
		(pad "OA11" smd rect
			(at -24.400002 3.934968)
			(size 0.381 1.7272)
			(layers "B.Cu" "B.Mask" "B.Paste")
			(net "I3C4_SPD_SCL")
		)
		(pad "OA12" smd rect
			(at -23.800054 3.934968)
			(size 0.381 1.7272)
			(layers "B.Cu" "B.Mask" "B.Paste")
			(net "I3C4_SPD_SDA")
		)
		(pad "OA13" smd rect
			(at -23.200106 4.13512)
			(size 0.381 2.1336)
			(layers "B.Cu" "B.Mask" "B.Paste")
			(net "GND")
		)
		(pad "OA14" smd rect
			(at -22.599904 4.13512)
			(size 0.381 2.1336)
			(layers "B.Cu" "B.Mask" "B.Paste")
			(net "FM_VIRTUAL_RESEAT")
		)
		(pad "OB1" smd rect
			(at -30.39999 4.13512)
			(size 0.381 2.1336)
			(layers "B.Cu" "B.Mask" "B.Paste")
			(net "P12V_AUX")
		)
		(pad "OB2" smd rect
			(at -29.800042 4.13512)
			(size 0.381 2.1336)
			(layers "B.Cu" "B.Mask" "B.Paste")
			(net "P12V_AUX")
		)
		(pad "OB3" smd rect
			(at -29.200094 4.13512)
			(size 0.381 2.1336)
			(layers "B.Cu" "B.Mask" "B.Paste")
			(net "FM_PRSNT_0_R_N")
		)
		(pad "OB4" smd rect
			(at -28.599892 4.13512)
			(size 0.381 2.1336)
			(layers "B.Cu" "B.Mask" "B.Paste")
			(net "GND")
		)
		(pad "OB5" smd rect
			(at -27.999944 4.13512)
			(size 0.381 2.1336)
			(layers "B.Cu" "B.Mask" "B.Paste")
			(net "UART_BIC_GF_TXD")
		)
		(pad "OB6" smd rect
			(at -27.399996 4.13512)
			(size 0.381 2.1336)
			(layers "B.Cu" "B.Mask" "B.Paste")
			(net "UART_BIC_GF_RXD")
		)
		(pad "OB7" smd rect
			(at -26.800048 4.13512)
			(size 0.381 2.1336)
			(layers "B.Cu" "B.Mask" "B.Paste")
			(net "GND")
		)
		(pad "OB8" smd rect
			(at -26.2001 4.13512)
			(size 0.381 2.1336)
			(layers "B.Cu" "B.Mask" "B.Paste")
			(net "UART_SYS_DBG_TX")
		)
		(pad "OB9" smd rect
			(at -25.599898 4.13512)
			(size 0.381 2.1336)
			(layers "B.Cu" "B.Mask" "B.Paste")
			(net "UART_SYS_DBG_RX")
		)
		(pad "OB10" smd rect
			(at -24.99995 4.13512)
			(size 0.381 2.1336)
			(layers "B.Cu" "B.Mask" "B.Paste")
			(net "GND")
		)
		(pad "OB11" smd rect
			(at -24.400002 3.934968)
			(size 0.381 1.7272)
			(layers "B.Cu" "B.Mask" "B.Paste")
			(net "RST_SRST_PLD_BMC_R_N")
		)
		(pad "OB12" smd rect
			(at -23.800054 3.934968)
			(size 0.381 1.7272)
			(layers "B.Cu" "B.Mask" "B.Paste")
			(net "SPI_TPM_CS_N")
		)
		(pad "OB13" smd rect
			(at -23.200106 4.13512)
			(size 0.381 2.1336)
			(layers "B.Cu" "B.Mask" "B.Paste")
			(net "H_CPU_CATERR_LVC2_R2_N")
		)
		(pad "OB14" smd rect
			(at -22.599904 4.13512)
			(size 0.381 2.1336)
			(layers "B.Cu" "B.Mask" "B.Paste")
			(net "FM_SOL_UART_CH_SEL")
		)
	)
)
